(kicad_pcb
	(version 20260206)
	(generator "pcbnew")
	(generator_version "10.0")
	(general
		(thickness 1.6)
		(legacy_teardrops no)
	)
	(paper "A4")
	(title_block
		(title "Wiwynn_Tioga_Pass_MB.brd")
		(comment 1 "Tioga Pass / footprints 1708-1714 of 4770")
	)
	(layers
		(0 "F.Cu" signal "TOP")
		(4 "In1.Cu" signal "L2GND")
		(6 "In2.Cu" signal "L3")
		(8 "In3.Cu" signal "L4GND")
		(10 "In4.Cu" signal "L5")
		(12 "In5.Cu" signal "L6GND")
		(14 "In6.Cu" signal "L7VCC")
		(16 "In7.Cu" signal "L8VCC")
		(18 "In8.Cu" signal "L9GND")
		(20 "In9.Cu" signal "L10")
		(22 "In10.Cu" signal "L11GND")
		(24 "In11.Cu" signal "L12")
		(26 "In12.Cu" signal "L13GND")
		(2 "B.Cu" signal "BOTTOM")
		(9 "F.Adhes" user "F.Adhesive")
		(11 "B.Adhes" user "B.Adhesive")
		(13 "F.Paste" user "Package Geometry/Pastemask Top")
		(15 "B.Paste" user "Package Geometry/Pastemask Bottom")
		(5 "F.SilkS" user "Ref Des/Silkscreen Top")
		(7 "B.SilkS" user "Ref Des/Silkscreen Bottom")
		(1 "F.Mask" user "Board Geometry/Soldermask Top")
		(3 "B.Mask" user "Board Geometry/Soldermask Bottom")
		(17 "Dwgs.User" user "User.Drawings")
		(19 "Cmts.User" user "User.Comments")
		(21 "Eco1.User" user "User.Eco1")
		(23 "Eco2.User" user "User.Eco2")
		(25 "Edge.Cuts" user "Board Geometry/Outline")
		(27 "Margin" user)
		(31 "F.CrtYd" user "Package Geometry/Place Bound Top")
		(29 "B.CrtYd" user "Package Geometry/Place Bound Bottom")
		(35 "F.Fab" user "Ref Des/Assembly Top")
		(33 "B.Fab" user "Ref Des/Assembly Bottom")
	)
	(footprint ""
		(layer "F.Cu")
		(at 169.247058 -105.4354)
		(property "Reference" "C4C1"
			(at -3.104388 3.8354 90)
			(unlocked yes)
			(layer "F.SilkS")
			(effects
				(font
					(size 0.7874 0.5842)
					(thickness 0.1524)
				)
			)
		)
		(property "Value" ""
			(at 0 0 0)
			(layer "F.Fab")
			(effects
				(font
					(size 1.27 1.27)
				)
			)
		)
		(duplicate_pad_numbers_are_jumpers no)
		(fp_line
			(start -2.563114 -1.616456)
			(end -2.563114 1.633728)
			(stroke
				(width 0.1524)
				(type default)
			)
			(layer "F.SilkS")
		)
		(fp_line
			(start -2.563114 1.633728)
			(end -1.6002 1.633728)
			(stroke
				(width 0.1524)
				(type default)
			)
			(layer "F.SilkS")
		)
		(fp_line
			(start -2.286 7.366)
			(end -2.286 1.632712)
			(stroke
				(width 0.1524)
				(type default)
			)
			(layer "F.SilkS")
		)
		(fp_line
			(start -2.286 7.366)
			(end -1.60147 7.366)
			(stroke
				(width 0.1524)
				(type default)
			)
			(layer "F.SilkS")
		)
		(fp_line
			(start -1.6002 -1.616456)
			(end -2.563114 -1.616456)
			(stroke
				(width 0.1524)
				(type default)
			)
			(layer "F.SilkS")
		)
		(fp_line
			(start 1.6002 -1.616456)
			(end 2.504948 -1.616456)
			(stroke
				(width 0.1524)
				(type default)
			)
			(layer "F.SilkS")
		)
		(fp_line
			(start 2.286 7.366)
			(end 1.600708 7.366)
			(stroke
				(width 0.1524)
				(type default)
			)
			(layer "F.SilkS")
		)
		(fp_line
			(start 2.286 7.366)
			(end 2.286 1.63195)
			(stroke
				(width 0.1524)
				(type default)
			)
			(layer "F.SilkS")
		)
		(fp_line
			(start 2.504948 -1.616456)
			(end 2.504948 1.633728)
			(stroke
				(width 0.1524)
				(type default)
			)
			(layer "F.SilkS")
		)
		(fp_line
			(start 2.504948 1.633728)
			(end 1.6002 1.633728)
			(stroke
				(width 0.1524)
				(type default)
			)
			(layer "F.SilkS")
		)
		(fp_rect
			(start -2.286 7.366)
			(end 2.286 -0.254)
			(stroke
				(width 0)
				(type default)
			)
			(fill no)
			(layer "F.CrtYd")
		)
		(fp_line
			(start -2.286 -0.254)
			(end 2.286 -0.254)
			(stroke
				(width 0.1)
				(type default)
			)
			(layer "F.Fab")
		)
		(fp_line
			(start -2.286 7.366)
			(end -2.286 -0.254)
			(stroke
				(width 0.1)
				(type default)
			)
			(layer "F.Fab")
		)
		(fp_line
			(start 2.286 -0.254)
			(end 2.286 7.366)
			(stroke
				(width 0.1)
				(type default)
			)
			(layer "F.Fab")
		)
		(fp_line
			(start 2.286 7.366)
			(end -2.286 7.366)
			(stroke
				(width 0.1)
				(type default)
			)
			(layer "F.Fab")
		)
		(pad "1" smd rect
			(at 0 0)
			(size 2.54 3.048)
			(layers "F.Cu" "F.Mask" "F.Paste")
			(net "PVCCIOMCP_CPU1")
		)
		(pad "2" smd rect
			(at 0 7.112)
			(size 2.54 3.048)
			(layers "F.Cu" "F.Mask" "F.Paste")
			(net "GND")
		)
	)
	(footprint ""
		(layer "F.Cu")
		(at 392.557 -88.2015)
		(property "Reference" "R3P62"
			(at 0 0 0)
			(layer "F.SilkS")
			(hide yes)
			(effects
				(font
					(size 1.27 1.27)
				)
			)
		)
		(property "Value" ""
			(at 0 0 0)
			(layer "F.Fab")
			(effects
				(font
					(size 1.27 1.27)
				)
			)
		)
		(duplicate_pad_numbers_are_jumpers no)
		(fp_poly
			(pts
				(xy -0.2794 -0.1016) (xy 0.2794 -0.1016) (xy 0.2794 0.9906) (xy -0.2794 0.9906)
			)
			(stroke
				(width 0)
				(type default)
			)
			(fill no)
			(layer "F.CrtYd")
		)
		(fp_line
			(start -0.2794 -0.1016)
			(end -0.2794 0.9906)
			(stroke
				(width 0.1)
				(type default)
			)
			(layer "F.Fab")
		)
		(fp_line
			(start -0.2794 0.9906)
			(end 0.2794 0.9906)
			(stroke
				(width 0.1)
				(type default)
			)
			(layer "F.Fab")
		)
		(fp_line
			(start 0.2794 -0.1016)
			(end -0.2794 -0.1016)
			(stroke
				(width 0.1)
				(type default)
			)
			(layer "F.Fab")
		)
		(fp_line
			(start 0.2794 0.9906)
			(end 0.2794 -0.1016)
			(stroke
				(width 0.1)
				(type default)
			)
			(layer "F.Fab")
		)
		(pad "1" smd rect
			(at 0 0)
			(size 0.508 0.508)
			(layers "F.Cu" "F.Mask" "F.Paste")
			(net "P3V3_STBY")
		)
		(pad "2" smd rect
			(at 0 0.889)
			(size 0.508 0.508)
			(layers "F.Cu" "F.Mask" "F.Paste")
			(net "FM_FLASH_ATTACH_CFG_STRAP")
		)
		(zone
			(layer "F.Cu")
			(hatch none 0.5)
			(connect_pads
				(clearance 0)
			)
			(min_thickness 0.25)
			(keepout
				(tracks allowed)
				(vias not_allowed)
				(pads allowed)
				(copperpour not_allowed)
				(footprints allowed)
			)
			(placement
				(enabled no)
				(sheetname "")
			)
			(fill
				(thermal_gap 0.5)
				(thermal_bridge_width 0.5)
				(island_removal_mode 0)
			)
			(polygon
				(pts
					(xy 392.303 -87.9475) (xy 392.811 -87.9475) (xy 392.811 -87.5665) (xy 392.303 -87.5665)
				)
			)
		)
		(zone
			(layer "F.Cu")
			(hatch none 0.5)
			(connect_pads
				(clearance 0)
			)
			(min_thickness 0.25)
			(keepout
				(tracks not_allowed)
				(vias allowed)
				(pads allowed)
				(copperpour not_allowed)
				(footprints allowed)
			)
			(placement
				(enabled no)
				(sheetname "")
			)
			(fill
				(thermal_gap 0.5)
				(thermal_bridge_width 0.5)
				(island_removal_mode 0)
			)
			(polygon
				(pts
					(xy 392.303 -87.5665) (xy 392.811 -87.5665) (xy 392.811 -87.9475) (xy 392.303 -87.9475)
				)
			)
		)
	)
	(footprint ""
		(layer "F.Cu")
		(at 29.028136 -22.994366)
		(property "Reference" "R1F5"
			(at 0 0 0)
			(layer "F.SilkS")
			(hide yes)
			(effects
				(font
					(size 1.27 1.27)
				)
			)
		)
		(property "Value" ""
			(at 0 0 0)
			(layer "F.Fab")
			(effects
				(font
					(size 1.27 1.27)
				)
			)
		)
		(duplicate_pad_numbers_are_jumpers no)
		(fp_poly
			(pts
				(xy -0.2794 -0.1016) (xy 0.2794 -0.1016) (xy 0.2794 0.9906) (xy -0.2794 0.9906)
			)
			(stroke
				(width 0)
				(type default)
			)
			(fill no)
			(layer "F.CrtYd")
		)
		(fp_line
			(start -0.2794 -0.1016)
			(end -0.2794 0.9906)
			(stroke
				(width 0.1)
				(type default)
			)
			(layer "F.Fab")
		)
		(fp_line
			(start -0.2794 0.9906)
			(end 0.2794 0.9906)
			(stroke
				(width 0.1)
				(type default)
			)
			(layer "F.Fab")
		)
		(fp_line
			(start 0.2794 -0.1016)
			(end -0.2794 -0.1016)
			(stroke
				(width 0.1)
				(type default)
			)
			(layer "F.Fab")
		)
		(fp_line
			(start 0.2794 0.9906)
			(end 0.2794 -0.1016)
			(stroke
				(width 0.1)
				(type default)
			)
			(layer "F.Fab")
		)
		(pad "1" smd rect
			(at 0 0)
			(size 0.508 0.508)
			(layers "F.Cu" "F.Mask" "F.Paste")
			(net "PVDDQ_GHJ")
		)
		(pad "2" smd rect
			(at 0 0.889)
			(size 0.508 0.508)
			(layers "F.Cu" "F.Mask" "F.Paste")
			(net "M_G_VREF")
		)
		(zone
			(layer "F.Cu")
			(hatch none 0.5)
			(connect_pads
				(clearance 0)
			)
			(min_thickness 0.25)
			(keepout
				(tracks allowed)
				(vias not_allowed)
				(pads allowed)
				(copperpour not_allowed)
				(footprints allowed)
			)
			(placement
				(enabled no)
				(sheetname "")
			)
			(fill
				(thermal_gap 0.5)
				(thermal_bridge_width 0.5)
				(island_removal_mode 0)
			)
			(polygon
				(pts
					(xy 28.774136 -22.740366) (xy 29.282136 -22.740366) (xy 29.282136 -22.359366) (xy 28.774136 -22.359366)
				)
			)
		)
		(zone
			(layer "F.Cu")
			(hatch none 0.5)
			(connect_pads
				(clearance 0)
			)
			(min_thickness 0.25)
			(keepout
				(tracks not_allowed)
				(vias allowed)
				(pads allowed)
				(copperpour not_allowed)
				(footprints allowed)
			)
			(placement
				(enabled no)
				(sheetname "")
			)
			(fill
				(thermal_gap 0.5)
				(thermal_bridge_width 0.5)
				(island_removal_mode 0)
			)
			(polygon
				(pts
					(xy 28.774136 -22.359366) (xy 29.282136 -22.359366) (xy 29.282136 -22.740366) (xy 28.774136 -22.740366)
				)
			)
		)
	)
	(footprint ""
		(layer "F.Cu")
		(at 8.991346 3.786124 -90)
		(property "Reference" "R1G22"
			(at 0 0 270)
			(layer "F.SilkS")
			(hide yes)
			(effects
				(font
					(size 1.27 1.27)
				)
			)
		)
		(property "Value" ""
			(at 0 0 270)
			(layer "F.Fab")
			(effects
				(font
					(size 1.27 1.27)
				)
			)
		)
		(duplicate_pad_numbers_are_jumpers no)
		(fp_poly
			(pts
				(xy -0.2794 -0.1016) (xy 0.2794 -0.1016) (xy 0.2794 0.9906) (xy -0.2794 0.9906)
			)
			(stroke
				(width 0)
				(type default)
			)
			(fill no)
			(layer "F.CrtYd")
		)
		(fp_line
			(start -0.2794 0.9906)
			(end 0.2794 0.9906)
			(stroke
				(width 0.1)
				(type default)
			)
			(layer "F.Fab")
		)
		(fp_line
			(start 0.2794 0.9906)
			(end 0.2794 -0.1016)
			(stroke
				(width 0.1)
				(type default)
			)
			(layer "F.Fab")
		)
		(fp_line
			(start -0.2794 -0.1016)
			(end -0.2794 0.9906)
			(stroke
				(width 0.1)
				(type default)
			)
			(layer "F.Fab")
		)
		(fp_line
			(start 0.2794 -0.1016)
			(end -0.2794 -0.1016)
			(stroke
				(width 0.1)
				(type default)
			)
			(layer "F.Fab")
		)
		(pad "1" smd rect
			(at 0 0 270)
			(size 0.508 0.508)
			(layers "F.Cu" "F.Mask" "F.Paste")
			(net "VR_PVDDQ_GHJ_XADDR2")
		)
		(pad "2" smd rect
			(at 0 0.889 270)
			(size 0.508 0.508)
			(layers "F.Cu" "F.Mask" "F.Paste")
			(net "GND")
		)
		(zone
			(layer "F.Cu")
			(hatch none 0.5)
			(connect_pads
				(clearance 0)
			)
			(min_thickness 0.25)
			(keepout
				(tracks not_allowed)
				(vias allowed)
				(pads allowed)
				(copperpour not_allowed)
				(footprints allowed)
			)
			(placement
				(enabled no)
				(sheetname "")
			)
			(fill
				(thermal_gap 0.5)
				(thermal_bridge_width 0.5)
				(island_removal_mode 0)
			)
			(polygon
				(pts
					(xy 8.356346 3.532124) (xy 8.356346 4.040124) (xy 8.737346 4.040124) (xy 8.737346 3.532124)
				)
			)
		)
		(zone
			(layer "F.Cu")
			(hatch none 0.5)
			(connect_pads
				(clearance 0)
			)
			(min_thickness 0.25)
			(keepout
				(tracks allowed)
				(vias not_allowed)
				(pads allowed)
				(copperpour not_allowed)
				(footprints allowed)
			)
			(placement
				(enabled no)
				(sheetname "")
			)
			(fill
				(thermal_gap 0.5)
				(thermal_bridge_width 0.5)
				(island_removal_mode 0)
			)
			(polygon
				(pts
					(xy 8.737346 3.532124) (xy 8.737346 4.040124) (xy 8.356346 4.040124) (xy 8.356346 3.532124)
				)
			)
		)
	)
	(footprint ""
		(layer "F.Cu")
		(at 477.3041 -41.3004 90)
		(property "Reference" "R9E20"
			(at 0 0 90)
			(layer "F.SilkS")
			(hide yes)
			(effects
				(font
					(size 1.27 1.27)
				)
			)
		)
		(property "Value" ""
			(at 0 0 90)
			(layer "F.Fab")
			(effects
				(font
					(size 1.27 1.27)
				)
			)
		)
		(duplicate_pad_numbers_are_jumpers no)
		(fp_poly
			(pts
				(xy -0.2794 -0.1016) (xy 0.2794 -0.1016) (xy 0.2794 0.9906) (xy -0.2794 0.9906)
			)
			(stroke
				(width 0)
				(type default)
			)
			(fill no)
			(layer "F.CrtYd")
		)
		(fp_line
			(start 0.2794 -0.1016)
			(end -0.2794 -0.1016)
			(stroke
				(width 0.1)
				(type default)
			)
			(layer "F.Fab")
		)
		(fp_line
			(start -0.2794 -0.1016)
			(end -0.2794 0.9906)
			(stroke
				(width 0.1)
				(type default)
			)
			(layer "F.Fab")
		)
		(fp_line
			(start 0.2794 0.9906)
			(end 0.2794 -0.1016)
			(stroke
				(width 0.1)
				(type default)
			)
			(layer "F.Fab")
		)
		(fp_line
			(start -0.2794 0.9906)
			(end 0.2794 0.9906)
			(stroke
				(width 0.1)
				(type default)
			)
			(layer "F.Fab")
		)
		(pad "1" smd rect
			(at 0 0 90)
			(size 0.508 0.508)
			(layers "F.Cu" "F.Mask" "F.Paste")
			(net "XTAL_25MHZ_IN")
		)
		(pad "2" smd rect
			(at 0 0.889 90)
			(size 0.508 0.508)
			(layers "F.Cu" "F.Mask" "F.Paste")
			(net "XTAL_25MHZ_IN_R")
		)
		(zone
			(layer "F.Cu")
			(hatch none 0.5)
			(connect_pads
				(clearance 0)
			)
			(min_thickness 0.25)
			(keepout
				(tracks allowed)
				(vias not_allowed)
				(pads allowed)
				(copperpour not_allowed)
				(footprints allowed)
			)
			(placement
				(enabled no)
				(sheetname "")
			)
			(fill
				(thermal_gap 0.5)
				(thermal_bridge_width 0.5)
				(island_removal_mode 0)
			)
			(polygon
				(pts
					(xy 477.5581 -41.0464) (xy 477.5581 -41.5544) (xy 477.9391 -41.5544) (xy 477.9391 -41.0464)
				)
			)
		)
		(zone
			(layer "F.Cu")
			(hatch none 0.5)
			(connect_pads
				(clearance 0)
			)
			(min_thickness 0.25)
			(keepout
				(tracks not_allowed)
				(vias allowed)
				(pads allowed)
				(copperpour not_allowed)
				(footprints allowed)
			)
			(placement
				(enabled no)
				(sheetname "")
			)
			(fill
				(thermal_gap 0.5)
				(thermal_bridge_width 0.5)
				(island_removal_mode 0)
			)
			(polygon
				(pts
					(xy 477.9391 -41.0464) (xy 477.9391 -41.5544) (xy 477.5581 -41.5544) (xy 477.5581 -41.0464)
				)
			)
		)
	)
	(footprint ""
		(layer "F.Cu")
		(at 333.6798 -25.2603 90)
		(property "Reference" "R7F10"
			(at 0 0 90)
			(layer "F.SilkS")
			(hide yes)
			(effects
				(font
					(size 1.27 1.27)
				)
			)
		)
		(property "Value" ""
			(at 0 0 90)
			(layer "F.Fab")
			(effects
				(font
					(size 1.27 1.27)
				)
			)
		)
		(duplicate_pad_numbers_are_jumpers no)
		(fp_poly
			(pts
				(xy -0.4953 -0.2032) (xy 0.4953 -0.2032) (xy 0.4953 1.6002) (xy -0.4953 1.6002)
			)
			(stroke
				(width 0)
				(type default)
			)
			(fill no)
			(layer "F.CrtYd")
		)
		(fp_line
			(start 0.4953 -0.2032)
			(end 0.4953 1.6002)
			(stroke
				(width 0.1)
				(type default)
			)
			(layer "F.Fab")
		)
		(fp_line
			(start -0.4953 -0.2032)
			(end 0.4953 -0.2032)
			(stroke
				(width 0.1)
				(type default)
			)
			(layer "F.Fab")
		)
		(fp_line
			(start 0.4953 1.6002)
			(end -0.4953 1.6002)
			(stroke
				(width 0.1)
				(type default)
			)
			(layer "F.Fab")
		)
		(fp_line
			(start -0.4953 1.6002)
			(end -0.4953 -0.2032)
			(stroke
				(width 0.1)
				(type default)
			)
			(layer "F.Fab")
		)
		(pad "1" smd rect
			(at 0 0 90)
			(size 0.762 0.889)
			(layers "F.Cu" "F.Mask" "F.Paste")
			(net "PVPP_ABC")
		)
		(pad "2" smd rect
			(at 0 1.397 90)
			(size 0.762 0.889)
			(layers "F.Cu" "F.Mask" "F.Paste")
			(net "GND")
		)
		(zone
			(layer "F.Cu")
			(hatch none 0.5)
			(connect_pads
				(clearance 0)
			)
			(min_thickness 0.25)
			(keepout
				(tracks allowed)
				(vias not_allowed)
				(pads allowed)
				(copperpour not_allowed)
				(footprints allowed)
			)
			(placement
				(enabled no)
				(sheetname "")
			)
			(fill
				(thermal_gap 0.5)
				(thermal_bridge_width 0.5)
				(island_removal_mode 0)
			)
			(polygon
				(pts
					(xy 334.6323 -25.6413) (xy 334.1243 -25.6413) (xy 334.1243 -24.8793) (xy 334.6323 -24.8793)
				)
			)
		)
		(zone
			(layer "F.Cu")
			(hatch none 0.5)
			(connect_pads
				(clearance 0)
			)
			(min_thickness 0.25)
			(keepout
				(tracks not_allowed)
				(vias allowed)
				(pads allowed)
				(copperpour not_allowed)
				(footprints allowed)
			)
			(placement
				(enabled no)
				(sheetname "")
			)
			(fill
				(thermal_gap 0.5)
				(thermal_bridge_width 0.5)
				(island_removal_mode 0)
			)
			(polygon
				(pts
					(xy 334.6323 -24.8793) (xy 334.6323 -25.6413) (xy 334.1243 -25.6413) (xy 334.1243 -24.8793)
				)
			)
		)
	)
	(footprint ""
		(layer "F.Cu")
		(at 272.24101 -84.890102)
		(property "Reference" "C5D4"
			(at 0 0 0)
			(layer "F.SilkS")
			(hide yes)
			(effects
				(font
					(size 1.27 1.27)
				)
			)
		)
		(property "Value" ""
			(at 0 0 0)
			(layer "F.Fab")
			(effects
				(font
					(size 1.27 1.27)
				)
			)
		)
		(duplicate_pad_numbers_are_jumpers no)
		(fp_poly
			(pts
				(xy -0.4953 -0.2032) (xy 0.4953 -0.2032) (xy 0.4953 1.6002) (xy -0.4953 1.6002)
			)
			(stroke
				(width 0)
				(type default)
			)
			(fill no)
			(layer "F.CrtYd")
		)
		(fp_line
			(start -0.4953 -0.2032)
			(end 0.4953 -0.2032)
			(stroke
				(width 0.1)
				(type default)
			)
			(layer "F.Fab")
		)
		(fp_line
			(start -0.4953 1.6002)
			(end -0.4953 -0.2032)
			(stroke
				(width 0.1)
				(type default)
			)
			(layer "F.Fab")
		)
		(fp_line
			(start 0.4953 -0.2032)
			(end 0.4953 1.6002)
			(stroke
				(width 0.1)
				(type default)
			)
			(layer "F.Fab")
		)
		(fp_line
			(start 0.4953 1.6002)
			(end -0.4953 1.6002)
			(stroke
				(width 0.1)
				(type default)
			)
			(layer "F.Fab")
		)
		(pad "1" smd rect
			(at 0 0)
			(size 0.762 0.889)
			(layers "F.Cu" "F.Mask" "F.Paste")
			(net "PVDDQ_DEF")
		)
		(pad "2" smd rect
			(at 0 1.397)
			(size 0.762 0.889)
			(layers "F.Cu" "F.Mask" "F.Paste")
			(net "GND")
		)
		(zone
			(layer "F.Cu")
			(hatch none 0.5)
			(connect_pads
				(clearance 0)
			)
			(min_thickness 0.25)
			(keepout
				(tracks not_allowed)
				(vias allowed)
				(pads allowed)
				(copperpour not_allowed)
				(footprints allowed)
			)
			(placement
				(enabled no)
				(sheetname "")
			)
			(fill
				(thermal_gap 0.5)
				(thermal_bridge_width 0.5)
				(island_removal_mode 0)
			)
			(polygon
				(pts
					(xy 271.86001 -84.445602) (xy 272.62201 -84.445602) (xy 272.62201 -83.937602) (xy 271.86001 -83.937602)
				)
			)
		)
	)
)
